(kicad_pcb
	(version 20260206)
	(generator "pcbnew")
	(generator_version "10.0")
	(general
		(thickness 1.6)
		(legacy_teardrops no)
	)
	(paper "A4")
	(title_block
		(title "03242023_DA0F0TMBIJ0_F0T_Motherboard_J_brd_V01_OCP.brd")
		(comment 1 "Grand Teton / footprints 3707-3710 of 6105")
	)
	(layers
		(0 "F.Cu" signal "TOP")
		(4 "In1.Cu" signal "GND")
		(6 "In2.Cu" signal "IN1")
		(8 "In3.Cu" signal "GND1")
		(10 "In4.Cu" signal "IN2")
		(12 "In5.Cu" signal "GND2")
		(14 "In6.Cu" signal "IN3")
		(16 "In7.Cu" signal "GND3")
		(18 "In8.Cu" signal "VCC")
		(20 "In9.Cu" signal "VCC1")
		(22 "In10.Cu" signal "GND4")
		(24 "In11.Cu" signal "IN4")
		(26 "In12.Cu" signal "GND5")
		(28 "In13.Cu" signal "IN5")
		(30 "In14.Cu" signal "GND6")
		(32 "In15.Cu" signal "IN6")
		(34 "In16.Cu" signal "GND7")
		(2 "B.Cu" signal "BOTTOM")
		(9 "F.Adhes" user "F.Adhesive")
		(11 "B.Adhes" user "B.Adhesive")
		(13 "F.Paste" user "Package Geometry/Pastemask Top")
		(15 "B.Paste" user "Package Geometry/Pastemask Bottom")
		(5 "F.SilkS" user "Ref Des/Silkscreen Top")
		(7 "B.SilkS" user "Ref Des/Silkscreen Bottom")
		(1 "F.Mask" user "Board Geometry/Soldermask Top")
		(3 "B.Mask" user "Board Geometry/Soldermask Bottom")
		(17 "Dwgs.User" user "User.Drawings")
		(19 "Cmts.User" user "User.Comments")
		(21 "Eco1.User" user "User.Eco1")
		(23 "Eco2.User" user "User.Eco2")
		(25 "Edge.Cuts" user "Board Geometry/Outline")
		(27 "Margin" user)
		(31 "F.CrtYd" user "Package Geometry/Place Bound Top")
		(29 "B.CrtYd" user "Package Geometry/Place Bound Bottom")
		(35 "F.Fab" user "Ref Des/Assembly Top")
		(33 "B.Fab" user "Ref Des/Assembly Bottom")
	)
	(footprint ""
		(layer "F.Cu")
		(at 112.26546 -413.408368 180)
		(property "Reference" "U314"
			(at 3.34772 6.20903 0)
			(unlocked yes)
			(layer "F.SilkS")
			(effects
				(font
					(size 0.7874 0.5842)
					(thickness 0.1524)
				)
			)
		)
		(property "Value" ""
			(at 0 0 180)
			(layer "F.Fab")
			(effects
				(font
					(size 1.27 1.27)
				)
			)
		)
		(duplicate_pad_numbers_are_jumpers no)
		(fp_line
			(start 2.500122 2.500122)
			(end 2.500122 2.01676)
			(stroke
				(width 0.1524)
				(type default)
			)
			(layer "F.SilkS")
		)
		(fp_line
			(start 2.500122 -2.01676)
			(end 2.500122 -2.500122)
			(stroke
				(width 0.1524)
				(type default)
			)
			(layer "F.SilkS")
		)
		(fp_line
			(start 2.500122 -2.500122)
			(end 2.01676 -2.500122)
			(stroke
				(width 0.1524)
				(type default)
			)
			(layer "F.SilkS")
		)
		(fp_line
			(start 2.01676 2.500122)
			(end 2.500122 2.500122)
			(stroke
				(width 0.1524)
				(type default)
			)
			(layer "F.SilkS")
		)
		(fp_line
			(start -2.01676 -2.500122)
			(end -2.500122 -2.500122)
			(stroke
				(width 0.1524)
				(type default)
			)
			(layer "F.SilkS")
		)
		(fp_line
			(start -2.500122 2.500122)
			(end -2.01676 2.500122)
			(stroke
				(width 0.1524)
				(type default)
			)
			(layer "F.SilkS")
		)
		(fp_line
			(start -2.500122 2.01676)
			(end -2.500122 2.500122)
			(stroke
				(width 0.1524)
				(type default)
			)
			(layer "F.SilkS")
		)
		(fp_line
			(start -2.500122 -2.500122)
			(end -2.500122 -2.01676)
			(stroke
				(width 0.1524)
				(type default)
			)
			(layer "F.SilkS")
		)
		(fp_poly
			(pts
				(xy -4.209542 -1.276858) (xy -4.209542 -2.472182) (xy -3.014218 -1.87452)
			)
			(stroke
				(width 0)
				(type default)
			)
			(fill yes)
			(layer "F.SilkS")
		)
		(fp_line
			(start 2.500122 2.500122)
			(end 2.500122 -2.500122)
			(stroke
				(width 0.1)
				(type default)
			)
			(layer "F.Fab")
		)
		(fp_line
			(start 2.500122 -2.500122)
			(end -2.500122 -2.500122)
			(stroke
				(width 0.1)
				(type default)
			)
			(layer "F.Fab")
		)
		(fp_line
			(start -2.500122 2.500122)
			(end 2.500122 2.500122)
			(stroke
				(width 0.1)
				(type default)
			)
			(layer "F.Fab")
		)
		(fp_line
			(start -2.500122 -2.500122)
			(end -2.500122 2.500122)
			(stroke
				(width 0.1)
				(type default)
			)
			(layer "F.Fab")
		)
		(fp_poly
			(pts
				(xy -3.044698 -1.75006) (xy -4.240022 -1.152398) (xy -4.240022 -2.347722)
			)
			(stroke
				(width 0)
				(type default)
			)
			(fill yes)
			(layer "F.Fab")
		)
		(pad "1" smd rect
			(at -2.3749 -1.75006 90)
			(size 0.254 0.5588)
			(layers "F.Cu" "F.Mask" "F.Paste")
			(net "FM_9ZXL045_DEV_EN")
		)
		(pad "2" smd rect
			(at -2.3749 -1.249934 90)
			(size 0.254 0.5588)
			(layers "F.Cu" "F.Mask" "F.Paste")
			(net "P3V3_9ZXL045_VDDR")
		)
		(pad "3" smd rect
			(at -2.3749 -0.750062 90)
			(size 0.254 0.5588)
			(layers "F.Cu" "F.Mask" "F.Paste")
			(net "CLK_100M_GPU_SWB_REF_DP")
		)
		(pad "4" smd rect
			(at -2.3749 -0.249936 90)
			(size 0.254 0.5588)
			(layers "F.Cu" "F.Mask" "F.Paste")
			(net "CLK_100M_GPU_SWB_REF_DN")
		)
		(pad "5" smd rect
			(at -2.3749 0.249936 90)
			(size 0.254 0.5588)
			(layers "F.Cu" "F.Mask" "F.Paste")
			(net "CLK_9ZXL045_SADR0")
		)
		(pad "6" smd rect
			(at -2.3749 0.750062 90)
			(size 0.254 0.5588)
			(layers "F.Cu" "F.Mask" "F.Paste")
			(net "SMB_HOST_9ZXL045_3V3AUX_SDA")
		)
		(pad "7" smd rect
			(at -2.3749 1.249934 90)
			(size 0.254 0.5588)
			(layers "F.Cu" "F.Mask" "F.Paste")
			(net "SMB_HOST_9ZXL045_3V3AUX_SCL")
		)
		(pad "8" smd rect
			(at -2.3749 1.75006 90)
			(size 0.254 0.5588)
			(layers "F.Cu" "F.Mask" "F.Paste")
			(net "NC_U314_FBOUT_N")
		)
		(pad "9" smd rect
			(at -1.75006 2.3749 180)
			(size 0.254 0.5588)
			(layers "F.Cu" "F.Mask" "F.Paste")
			(net "NC_U314_FBOUT")
		)
		(pad "10" smd rect
			(at -1.249934 2.3749 180)
			(size 0.254 0.5588)
			(layers "F.Cu" "F.Mask" "F.Paste")
			(net "NC_U314_NC0")
		)
		(pad "11" smd rect
			(at -0.750062 2.3749 180)
			(size 0.254 0.5588)
			(layers "F.Cu" "F.Mask" "F.Paste")
			(net "NC_U314_NC1")
		)
		(pad "12" smd rect
			(at -0.249936 2.3749 180)
			(size 0.254 0.5588)
			(layers "F.Cu" "F.Mask" "F.Paste")
			(net "P3V3_9ZXL045_VDD")
		)
		(pad "13" smd rect
			(at 0.249936 2.3749 180)
			(size 0.254 0.5588)
			(layers "F.Cu" "F.Mask" "F.Paste")
			(net "CLK_100M_SWB_R_DP")
		)
		(pad "14" smd rect
			(at 0.750062 2.3749 180)
			(size 0.254 0.5588)
			(layers "F.Cu" "F.Mask" "F.Paste")
			(net "CLK_100M_SWB_R_DN")
		)
		(pad "15" smd rect
			(at 1.249934 2.3749 180)
			(size 0.254 0.5588)
			(layers "F.Cu" "F.Mask" "F.Paste")
			(net "FM_9ZXL045_0_OE_N")
		)
		(pad "16" smd rect
			(at 1.75006 2.3749 180)
			(size 0.254 0.5588)
			(layers "F.Cu" "F.Mask" "F.Paste")
			(net "P3V3_9ZXL045_VDD")
		)
		(pad "17" smd rect
			(at 2.3749 1.75006 270)
			(size 0.254 0.5588)
			(layers "F.Cu" "F.Mask" "F.Paste")
			(net "NC_U314_NC2")
		)
		(pad "18" smd rect
			(at 2.3749 1.249934 270)
			(size 0.254 0.5588)
			(layers "F.Cu" "F.Mask" "F.Paste")
			(net "FM_9ZXL045_1_OE_N")
		)
		(pad "19" smd rect
			(at 2.3749 0.750062 270)
			(size 0.254 0.5588)
			(layers "F.Cu" "F.Mask" "F.Paste")
			(net "CLK_100M_GPU_1_R_DP")
		)
		(pad "20" smd rect
			(at 2.3749 0.249936 270)
			(size 0.254 0.5588)
			(layers "F.Cu" "F.Mask" "F.Paste")
			(net "CLK_100M_GPU_1_R_DN")
		)
		(pad "21" smd rect
			(at 2.3749 -0.249936 270)
			(size 0.254 0.5588)
			(layers "F.Cu" "F.Mask" "F.Paste")
			(net "P3V3_9ZXL045_VDD")
		)
		(pad "22" smd rect
			(at 2.3749 -0.750062 270)
			(size 0.254 0.5588)
			(layers "F.Cu" "F.Mask" "F.Paste")
			(net "CLK_100M_GPU_2_R_DP")
		)
		(pad "23" smd rect
			(at 2.3749 -1.249934 270)
			(size 0.254 0.5588)
			(layers "F.Cu" "F.Mask" "F.Paste")
			(net "CLK_100M_GPU_2_R_DN")
		)
		(pad "24" smd rect
			(at 2.3749 -1.75006 270)
			(size 0.254 0.5588)
			(layers "F.Cu" "F.Mask" "F.Paste")
			(net "FM_9ZXL045_2_OE_N")
		)
		(pad "25" smd rect
			(at 1.75006 -2.3749)
			(size 0.254 0.5588)
			(layers "F.Cu" "F.Mask" "F.Paste")
			(net "P3V3_9ZXL045_VDD")
		)
		(pad "26" smd rect
			(at 1.249934 -2.3749)
			(size 0.254 0.5588)
			(layers "F.Cu" "F.Mask" "F.Paste")
			(net "FM_9ZXL045_3_OE_N")
		)
		(pad "27" smd rect
			(at 0.750062 -2.3749)
			(size 0.254 0.5588)
			(layers "F.Cu" "F.Mask" "F.Paste")
			(net "TP_CLK_100M_BUF_DIF3_DP")
		)
		(pad "28" smd rect
			(at 0.249936 -2.3749)
			(size 0.254 0.5588)
			(layers "F.Cu" "F.Mask" "F.Paste")
			(net "TP_CLK_100M_BUF_DIF3_DN")
		)
		(pad "29" smd rect
			(at -0.249936 -2.3749)
			(size 0.254 0.5588)
			(layers "F.Cu" "F.Mask" "F.Paste")
			(net "P3V3_9ZXL045_VDD")
		)
		(pad "30" smd rect
			(at -0.750062 -2.3749)
			(size 0.254 0.5588)
			(layers "F.Cu" "F.Mask" "F.Paste")
			(net "NC_U314_NC3")
		)
		(pad "31" smd rect
			(at -1.249934 -2.3749)
			(size 0.254 0.5588)
			(layers "F.Cu" "F.Mask" "F.Paste")
			(net "P3V3_9ZXL045_VDDA")
		)
		(pad "32" smd rect
			(at -1.75006 -2.3749)
			(size 0.254 0.5588)
			(layers "F.Cu" "F.Mask" "F.Paste")
			(net "CLK_9ZXL045_HIBW")
		)
		(pad "33" smd rect
			(at 0 0 180)
			(size 3.1496 3.1496)
			(layers "F.Cu" "F.Mask" "F.Paste")
			(net "GND")
		)
		(zone
			(layer "F.Cu")
			(hatch none 0.5)
			(connect_pads
				(clearance 0)
			)
			(min_thickness 0.25)
			(keepout
				(tracks not_allowed)
				(vias allowed)
				(pads allowed)
				(copperpour not_allowed)
				(footprints allowed)
			)
			(placement
				(enabled no)
				(sheetname "")
			)
			(fill
				(thermal_gap 0.5)
				(thermal_bridge_width 0.5)
				(island_removal_mode 0)
			)
			(polygon
				(pts
					(xy 114.31016 -415.453068) (xy 114.31016 -412.183834) (xy 113.89106 -412.183834) (xy 113.89106 -415.033968)
					(xy 110.63986 -415.033968) (xy 110.63986 -411.782768) (xy 113.89106 -411.782768) (xy 113.89106 -412.158434)
					(xy 114.31016 -412.158434) (xy 114.31016 -411.363668) (xy 110.22076 -411.363668) (xy 110.22076 -415.453068)
				)
			)
		)
	)
	(footprint ""
		(layer "F.Cu")
		(at 273.801078 -422.6433)
		(property "Reference" "R4652"
			(at 0 0 0)
			(layer "F.SilkS")
			(hide yes)
			(effects
				(font
					(size 1.27 1.27)
				)
			)
		)
		(property "Value" ""
			(at 0 0 0)
			(layer "F.Fab")
			(effects
				(font
					(size 1.27 1.27)
				)
			)
		)
		(duplicate_pad_numbers_are_jumpers no)
		(fp_line
			(start -0.7874 -0.4064)
			(end 0.7874 -0.4064)
			(stroke
				(width 0.1524)
				(type default)
			)
			(layer "F.SilkS")
		)
		(fp_line
			(start -0.7874 0.4064)
			(end -0.7874 -0.4064)
			(stroke
				(width 0.1524)
				(type default)
			)
			(layer "F.SilkS")
		)
		(fp_line
			(start 0.7874 -0.4064)
			(end 0.7874 0.4064)
			(stroke
				(width 0.1524)
				(type default)
			)
			(layer "F.SilkS")
		)
		(fp_line
			(start 0.7874 0.4064)
			(end -0.7874 0.4064)
			(stroke
				(width 0.1524)
				(type default)
			)
			(layer "F.SilkS")
		)
		(fp_line
			(start -0.67945 -0.305054)
			(end -0.12065 -0.305054)
			(stroke
				(width 0.1)
				(type default)
			)
			(layer "F.Fab")
		)
		(fp_line
			(start -0.67945 0.3048)
			(end -0.67945 -0.305054)
			(stroke
				(width 0.1)
				(type default)
			)
			(layer "F.Fab")
		)
		(fp_line
			(start -0.12065 -0.305054)
			(end -0.12065 -0.2794)
			(stroke
				(width 0.1)
				(type default)
			)
			(layer "F.Fab")
		)
		(fp_line
			(start -0.12065 -0.2794)
			(end 0.12065 -0.2794)
			(stroke
				(width 0.1)
				(type default)
			)
			(layer "F.Fab")
		)
		(fp_line
			(start -0.12065 0.2794)
			(end -0.12065 0.3048)
			(stroke
				(width 0.1)
				(type default)
			)
			(layer "F.Fab")
		)
		(fp_line
			(start -0.12065 0.3048)
			(end -0.67945 0.3048)
			(stroke
				(width 0.1)
				(type default)
			)
			(layer "F.Fab")
		)
		(fp_line
			(start 0.120396 0.2794)
			(end -0.12065 0.2794)
			(stroke
				(width 0.1)
				(type default)
			)
			(layer "F.Fab")
		)
		(fp_line
			(start 0.120396 0.3048)
			(end 0.120396 0.2794)
			(stroke
				(width 0.1)
				(type default)
			)
			(layer "F.Fab")
		)
		(fp_line
			(start 0.12065 -0.3048)
			(end 0.67945 -0.3048)
			(stroke
				(width 0.1)
				(type default)
			)
			(layer "F.Fab")
		)
		(fp_line
			(start 0.12065 -0.2794)
			(end 0.12065 -0.3048)
			(stroke
				(width 0.1)
				(type default)
			)
			(layer "F.Fab")
		)
		(fp_line
			(start 0.67945 -0.3048)
			(end 0.67945 0.3048)
			(stroke
				(width 0.1)
				(type default)
			)
			(layer "F.Fab")
		)
		(fp_line
			(start 0.67945 0.3048)
			(end 0.120396 0.3048)
			(stroke
				(width 0.1)
				(type default)
			)
			(layer "F.Fab")
		)
		(pad "1" smd circle
			(at -0.40005 0)
			(size 0 0)
			(layers "F.Cu" "F.Mask" "F.Paste")
			(net "A_HSC_LOW_DRAIN")
		)
		(pad "2" smd circle
			(at 0.40005 0)
			(size 0 0)
			(layers "F.Cu" "F.Mask" "F.Paste")
			(net "HSC_D_OC")
		)
	)
	(footprint ""
		(layer "F.Cu")
		(at 355.228144 -241.976656 -90)
		(property "Reference" "C1023"
			(at 0 0 270)
			(layer "F.SilkS")
			(hide yes)
			(effects
				(font
					(size 1.27 1.27)
				)
			)
		)
		(property "Value" ""
			(at 0 0 270)
			(layer "F.Fab")
			(effects
				(font
					(size 1.27 1.27)
				)
			)
		)
		(duplicate_pad_numbers_are_jumpers no)
		(fp_line
			(start -0.7874 0.4064)
			(end -0.7874 -0.4064)
			(stroke
				(width 0.1524)
				(type default)
			)
			(layer "F.SilkS")
		)
		(fp_line
			(start 0.7874 0.4064)
			(end -0.7874 0.4064)
			(stroke
				(width 0.1524)
				(type default)
			)
			(layer "F.SilkS")
		)
		(fp_line
			(start -0.7874 -0.4064)
			(end 0.7874 -0.4064)
			(stroke
				(width 0.1524)
				(type default)
			)
			(layer "F.SilkS")
		)
		(fp_line
			(start 0.7874 -0.4064)
			(end 0.7874 0.4064)
			(stroke
				(width 0.1524)
				(type default)
			)
			(layer "F.SilkS")
		)
		(fp_line
			(start -0.67945 0.3048)
			(end -0.67945 -0.305054)
			(stroke
				(width 0.1)
				(type default)
			)
			(layer "F.Fab")
		)
		(fp_line
			(start -0.12065 0.3048)
			(end -0.67945 0.3048)
			(stroke
				(width 0.1)
				(type default)
			)
			(layer "F.Fab")
		)
		(fp_line
			(start 0.120396 0.3048)
			(end 0.120396 0.2794)
			(stroke
				(width 0.1)
				(type default)
			)
			(layer "F.Fab")
		)
		(fp_line
			(start 0.67945 0.3048)
			(end 0.120396 0.3048)
			(stroke
				(width 0.1)
				(type default)
			)
			(layer "F.Fab")
		)
		(fp_line
			(start -0.12065 0.2794)
			(end -0.12065 0.3048)
			(stroke
				(width 0.1)
				(type default)
			)
			(layer "F.Fab")
		)
		(fp_line
			(start 0.120396 0.2794)
			(end -0.12065 0.2794)
			(stroke
				(width 0.1)
				(type default)
			)
			(layer "F.Fab")
		)
		(fp_line
			(start -0.12065 -0.2794)
			(end 0.12065 -0.2794)
			(stroke
				(width 0.1)
				(type default)
			)
			(layer "F.Fab")
		)
		(fp_line
			(start 0.12065 -0.2794)
			(end 0.12065 -0.3048)
			(stroke
				(width 0.1)
				(type default)
			)
			(layer "F.Fab")
		)
		(fp_line
			(start 0.12065 -0.3048)
			(end 0.67945 -0.3048)
			(stroke
				(width 0.1)
				(type default)
			)
			(layer "F.Fab")
		)
		(fp_line
			(start 0.67945 -0.3048)
			(end 0.67945 0.3048)
			(stroke
				(width 0.1)
				(type default)
			)
			(layer "F.Fab")
		)
		(fp_line
			(start -0.67945 -0.305054)
			(end -0.12065 -0.305054)
			(stroke
				(width 0.1)
				(type default)
			)
			(layer "F.Fab")
		)
		(fp_line
			(start -0.12065 -0.305054)
			(end -0.12065 -0.2794)
			(stroke
				(width 0.1)
				(type default)
			)
			(layer "F.Fab")
		)
		(pad "1" smd circle
			(at -0.40005 0 270)
			(size 0 0)
			(layers "F.Cu" "F.Mask" "F.Paste")
			(net "PVCCIN_CPU0")
		)
		(pad "2" smd circle
			(at 0.40005 0 270)
			(size 0 0)
			(layers "F.Cu" "F.Mask" "F.Paste")
			(net "GND")
		)
	)
	(footprint ""
		(layer "F.Cu")
		(at 200.58888 -108.422948 90)
		(property "Reference" "R1841"
			(at 0 0 90)
			(layer "F.SilkS")
			(hide yes)
			(effects
				(font
					(size 1.27 1.27)
				)
			)
		)
		(property "Value" ""
			(at 0 0 90)
			(layer "F.Fab")
			(effects
				(font
					(size 1.27 1.27)
				)
			)
		)
		(duplicate_pad_numbers_are_jumpers no)
		(fp_line
			(start 0.7874 -0.4064)
			(end 0.7874 0.4064)
			(stroke
				(width 0.1524)
				(type default)
			)
			(layer "F.SilkS")
		)
		(fp_line
			(start -0.7874 -0.4064)
			(end 0.7874 -0.4064)
			(stroke
				(width 0.1524)
				(type default)
			)
			(layer "F.SilkS")
		)
		(fp_line
			(start 0.7874 0.4064)
			(end -0.7874 0.4064)
			(stroke
				(width 0.1524)
				(type default)
			)
			(layer "F.SilkS")
		)
		(fp_line
			(start -0.7874 0.4064)
			(end -0.7874 -0.4064)
			(stroke
				(width 0.1524)
				(type default)
			)
			(layer "F.SilkS")
		)
		(fp_line
			(start -0.12065 -0.305054)
			(end -0.12065 -0.2794)
			(stroke
				(width 0.1)
				(type default)
			)
			(layer "F.Fab")
		)
		(fp_line
			(start -0.67945 -0.305054)
			(end -0.12065 -0.305054)
			(stroke
				(width 0.1)
				(type default)
			)
			(layer "F.Fab")
		)
		(fp_line
			(start 0.67945 -0.3048)
			(end 0.67945 0.3048)
			(stroke
				(width 0.1)
				(type default)
			)
			(layer "F.Fab")
		)
		(fp_line
			(start 0.12065 -0.3048)
			(end 0.67945 -0.3048)
			(stroke
				(width 0.1)
				(type default)
			)
			(layer "F.Fab")
		)
		(fp_line
			(start 0.12065 -0.2794)
			(end 0.12065 -0.3048)
			(stroke
				(width 0.1)
				(type default)
			)
			(layer "F.Fab")
		)
		(fp_line
			(start -0.12065 -0.2794)
			(end 0.12065 -0.2794)
			(stroke
				(width 0.1)
				(type default)
			)
			(layer "F.Fab")
		)
		(fp_line
			(start 0.120396 0.2794)
			(end -0.12065 0.2794)
			(stroke
				(width 0.1)
				(type default)
			)
			(layer "F.Fab")
		)
		(fp_line
			(start -0.12065 0.2794)
			(end -0.12065 0.3048)
			(stroke
				(width 0.1)
				(type default)
			)
			(layer "F.Fab")
		)
		(fp_line
			(start 0.67945 0.3048)
			(end 0.120396 0.3048)
			(stroke
				(width 0.1)
				(type default)
			)
			(layer "F.Fab")
		)
		(fp_line
			(start 0.120396 0.3048)
			(end 0.120396 0.2794)
			(stroke
				(width 0.1)
				(type default)
			)
			(layer "F.Fab")
		)
		(fp_line
			(start -0.12065 0.3048)
			(end -0.67945 0.3048)
			(stroke
				(width 0.1)
				(type default)
			)
			(layer "F.Fab")
		)
		(fp_line
			(start -0.67945 0.3048)
			(end -0.67945 -0.305054)
			(stroke
				(width 0.1)
				(type default)
			)
			(layer "F.Fab")
		)
		(pad "1" smd circle
			(at -0.40005 0 90)
			(size 0 0)
			(layers "F.Cu" "F.Mask" "F.Paste")
			(net "P3V3_AUX")
		)
		(pad "2" smd circle
			(at 0.40005 0 90)
			(size 0 0)
			(layers "F.Cu" "F.Mask" "F.Paste")
			(net "FM_CPU_RMCA_CATERR_LVT3_R_N")
		)
	)
)
